# T6G (Grand Teton) — schematic netlist excerpt (pin names and nets, part order shuffled) for the footprints in the layout excerpt that follows; sources: Cadence DE-HDL packaged netlist, KiCad conversion of 04192023_DAF0TMB3IC0_F0TG_MB_C_brd_V02_OCP.brd

R517  Q_RES  2.2K 5% CHIP  pkg 0402LF  page 54 : A = P3V3_AUX ; B = CPU1_SP5R2
R3035  Q_RES  100K 1% CHIP  pkg 0402LF  page 127 : A = P3V3_AUX ; B = FM_SMB_2_ALERT_GPU_ISO_N

(kicad_pcb
	(version 20260206)
	(generator "pcbnew")
	(generator_version "10.0")
	(general
		(thickness 1.6)
		(legacy_teardrops no)
	)
	(paper "A4")
	(title_block
		(title "04192023_DAF0TMB3IC0_F0TG_MB_C_brd_V02_OCP.brd")
		(comment 1 "Grand Teton / footprints 5423-5424 of 8354")
	)
	(layers
		(0 "F.Cu" signal "TOP")
		(4 "In1.Cu" signal "GND")
		(6 "In2.Cu" signal "IN1")
		(8 "In3.Cu" signal "GND1")
		(10 "In4.Cu" signal "IN2")
		(12 "In5.Cu" signal "GND2")
		(14 "In6.Cu" signal "IN3")
		(16 "In7.Cu" signal "GND3")
		(18 "In8.Cu" signal "VCC")
		(20 "In9.Cu" signal "VCC1")
		(22 "In10.Cu" signal "GND4")
		(24 "In11.Cu" signal "IN4")
		(26 "In12.Cu" signal "GND5")
		(28 "In13.Cu" signal "IN5")
		(30 "In14.Cu" signal "GND6")
		(32 "In15.Cu" signal "IN6")
		(34 "In16.Cu" signal "GND7")
		(2 "B.Cu" signal "BOTTOM")
		(9 "F.Adhes" user "F.Adhesive")
		(11 "B.Adhes" user "B.Adhesive")
		(13 "F.Paste" user "Package Geometry/Pastemask Top")
		(15 "B.Paste" user "Package Geometry/Pastemask Bottom")
		(5 "F.SilkS" user "Ref Des/Silkscreen Top")
		(7 "B.SilkS" user "Ref Des/Silkscreen Bottom")
		(1 "F.Mask" user "Board Geometry/Soldermask Top")
		(3 "B.Mask" user "Board Geometry/Soldermask Bottom")
		(17 "Dwgs.User" user "User.Drawings")
		(19 "Cmts.User" user "User.Comments")
		(21 "Eco1.User" user "User.Eco1")
		(23 "Eco2.User" user "User.Eco2")
		(25 "Edge.Cuts" user "Board Geometry/Outline")
		(27 "Margin" user)
		(31 "F.CrtYd" user "Package Geometry/Place Bound Top")
		(29 "B.CrtYd" user "Package Geometry/Place Bound Bottom")
		(35 "F.Fab" user "Ref Des/Assembly Top")
		(33 "B.Fab" user "Ref Des/Assembly Bottom")
	)
	(footprint ""
		(layer "B.Cu")
		(at 70.172834 -203.679552 180)
		(property "Reference" "R517"
			(at 0 0 0)
			(layer "B.SilkS")
			(hide yes)
			(effects
				(font
					(size 1.27 1.27)
				)
				(justify mirror)
			)
		)
		(property "Value" ""
			(at 0 0 0)
			(layer "B.Fab")
			(effects
				(font
					(size 1.27 1.27)
				)
				(justify mirror)
			)
		)
		(duplicate_pad_numbers_are_jumpers no)
		(fp_line
			(start 0.7874 0.4064)
			(end 0.7874 -0.4064)
			(stroke
				(width 0.1524)
				(type default)
			)
			(layer "B.SilkS")
		)
		(fp_line
			(start 0.7874 -0.4064)
			(end -0.7874 -0.4064)
			(stroke
				(width 0.1524)
				(type default)
			)
			(layer "B.SilkS")
		)
		(fp_line
			(start -0.7874 0.4064)
			(end 0.7874 0.4064)
			(stroke
				(width 0.1524)
				(type default)
			)
			(layer "B.SilkS")
		)
		(fp_line
			(start -0.7874 -0.4064)
			(end -0.7874 0.4064)
			(stroke
				(width 0.1524)
				(type default)
			)
			(layer "B.SilkS")
		)
		(fp_line
			(start 0.67945 0.3048)
			(end 0.67945 -0.305054)
			(stroke
				(width 0.1)
				(type default)
			)
			(layer "B.Fab")
		)
		(fp_line
			(start 0.67945 -0.305054)
			(end 0.12065 -0.305054)
			(stroke
				(width 0.1)
				(type default)
			)
			(layer "B.Fab")
		)
		(fp_line
			(start 0.12065 0.3048)
			(end 0.67945 0.3048)
			(stroke
				(width 0.1)
				(type default)
			)
			(layer "B.Fab")
		)
		(fp_line
			(start 0.12065 0.2794)
			(end 0.12065 0.3048)
			(stroke
				(width 0.1)
				(type default)
			)
			(layer "B.Fab")
		)
		(fp_line
			(start 0.12065 -0.2794)
			(end -0.12065 -0.2794)
			(stroke
				(width 0.1)
				(type default)
			)
			(layer "B.Fab")
		)
		(fp_line
			(start 0.12065 -0.305054)
			(end 0.12065 -0.2794)
			(stroke
				(width 0.1)
				(type default)
			)
			(layer "B.Fab")
		)
		(fp_line
			(start -0.120396 0.3048)
			(end -0.120396 0.2794)
			(stroke
				(width 0.1)
				(type default)
			)
			(layer "B.Fab")
		)
		(fp_line
			(start -0.120396 0.2794)
			(end 0.12065 0.2794)
			(stroke
				(width 0.1)
				(type default)
			)
			(layer "B.Fab")
		)
		(fp_line
			(start -0.12065 -0.2794)
			(end -0.12065 -0.3048)
			(stroke
				(width 0.1)
				(type default)
			)
			(layer "B.Fab")
		)
		(fp_line
			(start -0.12065 -0.3048)
			(end -0.67945 -0.3048)
			(stroke
				(width 0.1)
				(type default)
			)
			(layer "B.Fab")
		)
		(fp_line
			(start -0.67945 0.3048)
			(end -0.120396 0.3048)
			(stroke
				(width 0.1)
				(type default)
			)
			(layer "B.Fab")
		)
		(fp_line
			(start -0.67945 -0.3048)
			(end -0.67945 0.3048)
			(stroke
				(width 0.1)
				(type default)
			)
			(layer "B.Fab")
		)
		(pad "1" smd circle
			(at 0.40005 0)
			(size 0 0)
			(layers "B.Cu" "B.Mask" "B.Paste")
			(net "P3V3_AUX")
		)
		(pad "2" smd circle
			(at -0.40005 0)
			(size 0 0)
			(layers "B.Cu" "B.Mask" "B.Paste")
			(net "CPU1_SP5R2")
		)
	)
	(footprint ""
		(layer "B.Cu")
		(at 109.728 -417.83 -90)
		(property "Reference" "R3035"
			(at 0 0 90)
			(layer "B.SilkS")
			(hide yes)
			(effects
				(font
					(size 1.27 1.27)
				)
				(justify mirror)
			)
		)
		(property "Value" ""
			(at 0 0 90)
			(layer "B.Fab")
			(effects
				(font
					(size 1.27 1.27)
				)
				(justify mirror)
			)
		)
		(duplicate_pad_numbers_are_jumpers no)
		(fp_line
			(start -0.7874 0.4064)
			(end 0.7874 0.4064)
			(stroke
				(width 0.1524)
				(type default)
			)
			(layer "B.SilkS")
		)
		(fp_line
			(start 0.7874 0.4064)
			(end 0.7874 -0.4064)
			(stroke
				(width 0.1524)
				(type default)
			)
			(layer "B.SilkS")
		)
		(fp_line
			(start -0.7874 -0.4064)
			(end -0.7874 0.4064)
			(stroke
				(width 0.1524)
				(type default)
			)
			(layer "B.SilkS")
		)
		(fp_line
			(start 0.7874 -0.4064)
			(end -0.7874 -0.4064)
			(stroke
				(width 0.1524)
				(type default)
			)
			(layer "B.SilkS")
		)
		(fp_line
			(start -0.67945 0.3048)
			(end -0.120396 0.3048)
			(stroke
				(width 0.1)
				(type default)
			)
			(layer "B.Fab")
		)
		(fp_line
			(start -0.120396 0.3048)
			(end -0.120396 0.2794)
			(stroke
				(width 0.1)
				(type default)
			)
			(layer "B.Fab")
		)
		(fp_line
			(start 0.12065 0.3048)
			(end 0.67945 0.3048)
			(stroke
				(width 0.1)
				(type default)
			)
			(layer "B.Fab")
		)
		(fp_line
			(start 0.67945 0.3048)
			(end 0.67945 -0.305054)
			(stroke
				(width 0.1)
				(type default)
			)
			(layer "B.Fab")
		)
		(fp_line
			(start -0.120396 0.2794)
			(end 0.12065 0.2794)
			(stroke
				(width 0.1)
				(type default)
			)
			(layer "B.Fab")
		)
		(fp_line
			(start 0.12065 0.2794)
			(end 0.12065 0.3048)
			(stroke
				(width 0.1)
				(type default)
			)
			(layer "B.Fab")
		)
		(fp_line
			(start -0.12065 -0.2794)
			(end -0.12065 -0.3048)
			(stroke
				(width 0.1)
				(type default)
			)
			(layer "B.Fab")
		)
		(fp_line
			(start 0.12065 -0.2794)
			(end -0.12065 -0.2794)
			(stroke
				(width 0.1)
				(type default)
			)
			(layer "B.Fab")
		)
		(fp_line
			(start -0.67945 -0.3048)
			(end -0.67945 0.3048)
			(stroke
				(width 0.1)
				(type default)
			)
			(layer "B.Fab")
		)
		(fp_line
			(start -0.12065 -0.3048)
			(end -0.67945 -0.3048)
			(stroke
				(width 0.1)
				(type default)
			)
			(layer "B.Fab")
		)
		(fp_line
			(start 0.12065 -0.305054)
			(end 0.12065 -0.2794)
			(stroke
				(width 0.1)
				(type default)
			)
			(layer "B.Fab")
		)
		(fp_line
			(start 0.67945 -0.305054)
			(end 0.12065 -0.305054)
			(stroke
				(width 0.1)
				(type default)
			)
			(layer "B.Fab")
		)
		(pad "1" smd circle
			(at 0.40005 0 90)
			(size 0 0)
			(layers "B.Cu" "B.Mask" "B.Paste")
			(net "P3V3_AUX")
		)
		(pad "2" smd circle
			(at -0.40005 0 90)
			(size 0 0)
			(layers "B.Cu" "B.Mask" "B.Paste")
			(net "FM_SMB_2_ALERT_GPU_ISO_N")
		)
	)
)
